# T6G (Grand Teton) — schematic netlist excerpt (pin names and nets, part order shuffled) for the footprints in the layout excerpt that follows; sources: Cadence DE-HDL packaged netlist, KiCad conversion of 04192023_DAF0TMB3IC0_F0TG_MB_C_brd_V02_OCP.brd

C273  Q_CAP  22UF 4V 20% X6S  pkg C0402  page 69 : A = PVDDCR_CPU0_P0 ; B = GND

U324  MOSFET_NCH_GDS_ESD_PROTECTED  2N7002K IC  pkg SOT23_GDSXC  page 188
  D  = VR_P5V_EN_D
  G  = VR_P5V_EN_N
  S  = GND

(kicad_pcb
	(version 20260206)
	(generator "pcbnew")
	(generator_version "10.0")
	(general
		(thickness 1.6)
		(legacy_teardrops no)
	)
	(paper "A4")
	(title_block
		(title "04192023_DAF0TMB3IC0_F0TG_MB_C_brd_V02_OCP.brd")
		(comment 1 "Grand Teton / footprints 7154-7155 of 8354")
	)
	(layers
		(0 "F.Cu" signal "TOP")
		(4 "In1.Cu" signal "GND")
		(6 "In2.Cu" signal "IN1")
		(8 "In3.Cu" signal "GND1")
		(10 "In4.Cu" signal "IN2")
		(12 "In5.Cu" signal "GND2")
		(14 "In6.Cu" signal "IN3")
		(16 "In7.Cu" signal "GND3")
		(18 "In8.Cu" signal "VCC")
		(20 "In9.Cu" signal "VCC1")
		(22 "In10.Cu" signal "GND4")
		(24 "In11.Cu" signal "IN4")
		(26 "In12.Cu" signal "GND5")
		(28 "In13.Cu" signal "IN5")
		(30 "In14.Cu" signal "GND6")
		(32 "In15.Cu" signal "IN6")
		(34 "In16.Cu" signal "GND7")
		(2 "B.Cu" signal "BOTTOM")
		(9 "F.Adhes" user "F.Adhesive")
		(11 "B.Adhes" user "B.Adhesive")
		(13 "F.Paste" user "Package Geometry/Pastemask Top")
		(15 "B.Paste" user "Package Geometry/Pastemask Bottom")
		(5 "F.SilkS" user "Ref Des/Silkscreen Top")
		(7 "B.SilkS" user "Ref Des/Silkscreen Bottom")
		(1 "F.Mask" user "Board Geometry/Soldermask Top")
		(3 "B.Mask" user "Board Geometry/Soldermask Bottom")
		(17 "Dwgs.User" user "User.Drawings")
		(19 "Cmts.User" user "User.Comments")
		(21 "Eco1.User" user "User.Eco1")
		(23 "Eco2.User" user "User.Eco2")
		(25 "Edge.Cuts" user "Board Geometry/Outline")
		(27 "Margin" user)
		(31 "F.CrtYd" user "Package Geometry/Place Bound Top")
		(29 "B.CrtYd" user "Package Geometry/Place Bound Bottom")
		(35 "F.Fab" user "Ref Des/Assembly Top")
		(33 "B.Fab" user "Ref Des/Assembly Bottom")
	)
	(footprint ""
		(layer "B.Cu")
		(at 354.628958 -249.36831 180)
		(property "Reference" "C273"
			(at 0 0 0)
			(layer "B.SilkS")
			(hide yes)
			(effects
				(font
					(size 1.27 1.27)
				)
				(justify mirror)
			)
		)
		(property "Value" ""
			(at 0 0 0)
			(layer "B.Fab")
			(effects
				(font
					(size 1.27 1.27)
				)
				(justify mirror)
			)
		)
		(duplicate_pad_numbers_are_jumpers no)
		(fp_line
			(start 0.7874 0.4064)
			(end 0.7874 -0.4064)
			(stroke
				(width 0.1524)
				(type default)
			)
			(layer "B.SilkS")
		)
		(fp_line
			(start 0.7874 -0.4064)
			(end -0.7874 -0.4064)
			(stroke
				(width 0.1524)
				(type default)
			)
			(layer "B.SilkS")
		)
		(fp_line
			(start -0.7874 0.4064)
			(end 0.7874 0.4064)
			(stroke
				(width 0.1524)
				(type default)
			)
			(layer "B.SilkS")
		)
		(fp_line
			(start -0.7874 -0.4064)
			(end -0.7874 0.4064)
			(stroke
				(width 0.1524)
				(type default)
			)
			(layer "B.SilkS")
		)
		(fp_line
			(start 0.67945 0.3048)
			(end 0.67945 -0.305054)
			(stroke
				(width 0.1)
				(type default)
			)
			(layer "B.Fab")
		)
		(fp_line
			(start 0.67945 -0.305054)
			(end 0.12065 -0.305054)
			(stroke
				(width 0.1)
				(type default)
			)
			(layer "B.Fab")
		)
		(fp_line
			(start 0.12065 0.3048)
			(end 0.67945 0.3048)
			(stroke
				(width 0.1)
				(type default)
			)
			(layer "B.Fab")
		)
		(fp_line
			(start 0.12065 0.2794)
			(end 0.12065 0.3048)
			(stroke
				(width 0.1)
				(type default)
			)
			(layer "B.Fab")
		)
		(fp_line
			(start 0.12065 -0.2794)
			(end -0.12065 -0.2794)
			(stroke
				(width 0.1)
				(type default)
			)
			(layer "B.Fab")
		)
		(fp_line
			(start 0.12065 -0.305054)
			(end 0.12065 -0.2794)
			(stroke
				(width 0.1)
				(type default)
			)
			(layer "B.Fab")
		)
		(fp_line
			(start -0.120396 0.3048)
			(end -0.120396 0.2794)
			(stroke
				(width 0.1)
				(type default)
			)
			(layer "B.Fab")
		)
		(fp_line
			(start -0.120396 0.2794)
			(end 0.12065 0.2794)
			(stroke
				(width 0.1)
				(type default)
			)
			(layer "B.Fab")
		)
		(fp_line
			(start -0.12065 -0.2794)
			(end -0.12065 -0.3048)
			(stroke
				(width 0.1)
				(type default)
			)
			(layer "B.Fab")
		)
		(fp_line
			(start -0.12065 -0.3048)
			(end -0.67945 -0.3048)
			(stroke
				(width 0.1)
				(type default)
			)
			(layer "B.Fab")
		)
		(fp_line
			(start -0.67945 0.3048)
			(end -0.120396 0.3048)
			(stroke
				(width 0.1)
				(type default)
			)
			(layer "B.Fab")
		)
		(fp_line
			(start -0.67945 -0.3048)
			(end -0.67945 0.3048)
			(stroke
				(width 0.1)
				(type default)
			)
			(layer "B.Fab")
		)
		(pad "1" smd circle
			(at 0.40005 0)
			(size 0 0)
			(layers "B.Cu" "B.Mask" "B.Paste")
			(net "PVDDCR_CPU0_P0")
		)
		(pad "2" smd circle
			(at -0.40005 0)
			(size 0 0)
			(layers "B.Cu" "B.Mask" "B.Paste")
			(net "GND")
		)
	)
	(footprint ""
		(layer "B.Cu")
		(at 395.179296 -154.065986 180)
		(property "Reference" "U324"
			(at -0.98298 -2.36347 0)
			(unlocked yes)
			(layer "B.SilkS")
			(effects
				(font
					(size 0.7874 0.5842)
					(thickness 0.1524)
				)
				(justify left mirror)
			)
		)
		(property "Value" ""
			(at 0 0 0)
			(layer "B.Fab")
			(effects
				(font
					(size 1.27 1.27)
				)
				(justify mirror)
			)
		)
		(duplicate_pad_numbers_are_jumpers no)
		(fp_line
			(start 1.603248 1.500124)
			(end 1.603248 -1.500124)
			(stroke
				(width 0.1524)
				(type default)
			)
			(layer "B.SilkS")
		)
		(fp_line
			(start 1.603248 -1.500124)
			(end -1.603248 -1.500124)
			(stroke
				(width 0.1524)
				(type default)
			)
			(layer "B.SilkS")
		)
		(fp_line
			(start -1.603248 1.500124)
			(end 1.603248 1.500124)
			(stroke
				(width 0.1524)
				(type default)
			)
			(layer "B.SilkS")
		)
		(fp_line
			(start -1.603248 -1.500124)
			(end -1.603248 1.500124)
			(stroke
				(width 0.1524)
				(type default)
			)
			(layer "B.SilkS")
		)
		(fp_line
			(start 1.249934 1.169924)
			(end 0.700024 1.169924)
			(stroke
				(width 0.1)
				(type default)
			)
			(layer "B.Fab")
		)
		(fp_line
			(start 1.249934 0.729996)
			(end 1.249934 1.169924)
			(stroke
				(width 0.1)
				(type default)
			)
			(layer "B.Fab")
		)
		(fp_line
			(start 1.249934 -0.729996)
			(end 0.6985 -0.729996)
			(stroke
				(width 0.1)
				(type default)
			)
			(layer "B.Fab")
		)
		(fp_line
			(start 1.249934 -1.169924)
			(end 1.249934 -0.729996)
			(stroke
				(width 0.1)
				(type default)
			)
			(layer "B.Fab")
		)
		(fp_line
			(start 0.700024 1.500124)
			(end -0.700024 1.500124)
			(stroke
				(width 0.1)
				(type default)
			)
			(layer "B.Fab")
		)
		(fp_line
			(start 0.700024 1.169924)
			(end 0.700024 1.500124)
			(stroke
				(width 0.1)
				(type default)
			)
			(layer "B.Fab")
		)
		(fp_line
			(start 0.700024 -1.169924)
			(end 1.249934 -1.169924)
			(stroke
				(width 0.1)
				(type default)
			)
			(layer "B.Fab")
		)
		(fp_line
			(start 0.700024 -1.500124)
			(end 0.700024 -1.169924)
			(stroke
				(width 0.1)
				(type default)
			)
			(layer "B.Fab")
		)
		(fp_line
			(start 0.6985 0.729996)
			(end 1.249934 0.729996)
			(stroke
				(width 0.1)
				(type default)
			)
			(layer "B.Fab")
		)
		(fp_line
			(start 0.6985 -0.729996)
			(end 0.6985 0.729996)
			(stroke
				(width 0.1)
				(type default)
			)
			(layer "B.Fab")
		)
		(fp_line
			(start -0.700024 1.500124)
			(end -0.700024 0.219964)
			(stroke
				(width 0.1)
				(type default)
			)
			(layer "B.Fab")
		)
		(fp_line
			(start -0.700024 0.219964)
			(end -1.249934 0.219964)
			(stroke
				(width 0.1)
				(type default)
			)
			(layer "B.Fab")
		)
		(fp_line
			(start -0.700024 -0.219964)
			(end -0.700024 -1.500124)
			(stroke
				(width 0.1)
				(type default)
			)
			(layer "B.Fab")
		)
		(fp_line
			(start -0.700024 -1.500124)
			(end 0.700024 -1.500124)
			(stroke
				(width 0.1)
				(type default)
			)
			(layer "B.Fab")
		)
		(fp_line
			(start -1.249934 0.219964)
			(end -1.249934 -0.219964)
			(stroke
				(width 0.1)
				(type default)
			)
			(layer "B.Fab")
		)
		(fp_line
			(start -1.249934 -0.219964)
			(end -0.700024 -0.219964)
			(stroke
				(width 0.1)
				(type default)
			)
			(layer "B.Fab")
		)
		(fp_rect
			(start -0.700024 1.500124)
			(end 0.700024 -1.500124)
			(stroke
				(width 0)
				(type default)
			)
			(fill no)
			(layer "B.Fab")
		)
		(pad "D" smd rect
			(at -0.999998 0 90)
			(size 0.8128 0.9144)
			(layers "B.Cu" "B.Mask" "B.Paste")
			(net "VR_P5V_EN_D")
		)
		(pad "G" smd rect
			(at 0.999998 -0.94996 90)
			(size 0.8128 0.9144)
			(layers "B.Cu" "B.Mask" "B.Paste")
			(net "VR_P5V_EN_N")
		)
		(pad "S" smd rect
			(at 0.999998 0.94996 90)
			(size 0.8128 0.9144)
			(layers "B.Cu" "B.Mask" "B.Paste")
			(net "GND")
		)
	)
)
